(kicad_pcb
	(version 20241229)
	(generator "pcbnew")
	(generator_version "9.0")
	(general
		(thickness 1.294)
		(legacy_teardrops no)
	)
	(paper "A3")
	(title_block
		(title "Kintex 410T devboard")
		(date "2024-04-03")
		(rev "1.1.2")
		(comment 9 "footprints 1-5 of 975")
	)
	(layers
		(0 "F.Cu" mixed)
		(4 "In1.Cu" power)
		(6 "In2.Cu" power)
		(8 "In3.Cu" mixed)
		(10 "In4.Cu" power)
		(12 "In5.Cu" mixed)
		(14 "In6.Cu" power)
		(16 "In7.Cu" mixed)
		(18 "In8.Cu" power)
		(2 "B.Cu" mixed)
		(9 "F.Adhes" user "F.Adhesive")
		(11 "B.Adhes" user "B.Adhesive")
		(13 "F.Paste" user)
		(15 "B.Paste" user)
		(5 "F.SilkS" user "F.Silkscreen")
		(7 "B.SilkS" user "B.Silkscreen")
		(1 "F.Mask" user)
		(3 "B.Mask" user)
		(17 "Dwgs.User" user "User.Drawings")
		(19 "Cmts.User" user "User.Comments")
		(21 "Eco1.User" user "User.Eco1")
		(23 "Eco2.User" user "User.Eco2")
		(25 "Edge.Cuts" user)
		(27 "Margin" user)
		(31 "F.CrtYd" user "F.Courtyard")
		(29 "B.CrtYd" user "B.Courtyard")
		(35 "F.Fab" user)
		(33 "B.Fab" user)
	)
	(footprint "antmicro-footprints:C_0402_1005Metric"
		(layer "F.Cu")
		(at 195.803752 91.5615)
		(descr "Capacitor SMD 0402")
		(tags "capacitor SMD 0402")
		(property "Reference" "C286"
			(at -1.628752 -0.4365 0)
			(layer "F.SilkS")
			(effects
				(font
					(size 0.7 0.7)
					(thickness 0.15)
				)
				(justify left bottom)
			)
		)
		(property "Value" "C_100n_0402"
			(at 0 1.169 0)
			(layer "F.Fab")
			(effects
				(font
					(size 0.7 0.7)
					(thickness 0.15)
				)
				(justify left bottom)
			)
		)
		(property "Description" "SMD Multilayer Ceramic Capacitor, 0.1 µF, 50 V, 0402 [1005 Metric], ± 10%, X5R, GRM Series"
			(at 0 0 0)
			(layer "F.Fab")
			(hide yes)
			(effects
				(font
					(size 1.27 1.27)
					(thickness 0.15)
				)
			)
		)
		(property "Author" "Antmicro"
			(at 0 0 0)
			(layer "F.Fab")
			(hide yes)
			(effects
				(font
					(size 1 1)
					(thickness 0.15)
				)
			)
		)
		(property "Dielectric" "X5R"
			(at 0 0 0)
			(layer "F.Fab")
			(hide yes)
			(effects
				(font
					(size 1 1)
					(thickness 0.15)
				)
			)
		)
		(property "License" "Apache-2.0"
			(at 0 0 0)
			(layer "F.Fab")
			(hide yes)
			(effects
				(font
					(size 1 1)
					(thickness 0.15)
				)
			)
		)
		(property "MPN" "GRM155R61H104KE14D"
			(at 0 0 0)
			(layer "F.Fab")
			(hide yes)
			(effects
				(font
					(size 1 1)
					(thickness 0.15)
				)
			)
		)
		(property "Manufacturer" "Murata"
			(at 0 0 0)
			(layer "F.Fab")
			(hide yes)
			(effects
				(font
					(size 1 1)
					(thickness 0.15)
				)
			)
		)
		(property "Val" "100n"
			(at 0 0 0)
			(layer "F.Fab")
			(hide yes)
			(effects
				(font
					(size 1 1)
					(thickness 0.15)
				)
			)
		)
		(property "Voltage" "50V"
			(at 0 0 0)
			(layer "F.Fab")
			(hide yes)
			(effects
				(font
					(size 1 1)
					(thickness 0.15)
				)
			)
		)
		(sheetname "HDMI + Ethernet")
		(sheetfile "hdmi-ethernet.kicad_sch")
		(attr smd)
		(fp_rect
			(start -0.925 -0.47)
			(end 0.925 0.47)
			(stroke
				(width 0.05)
				(type default)
			)
			(fill no)
			(layer "F.CrtYd")
		)
		(fp_line
			(start -0.494 -0.25)
			(end 0.504 -0.25)
			(stroke
				(width 0.15)
				(type solid)
			)
			(layer "F.Fab")
		)
		(fp_line
			(start -0.494 0.248)
			(end -0.494 -0.25)
			(stroke
				(width 0.15)
				(type solid)
			)
			(layer "F.Fab")
		)
		(fp_line
			(start 0.504 -0.25)
			(end 0.504 0.248)
			(stroke
				(width 0.15)
				(type solid)
			)
			(layer "F.Fab")
		)
		(fp_line
			(start 0.504 0.248)
			(end -0.494 0.248)
			(stroke
				(width 0.15)
				(type solid)
			)
			(layer "F.Fab")
		)
		(pad "1" smd roundrect
			(at -0.48 0)
			(size 0.59 0.64)
			(layers "F.Cu" "F.Mask" "F.Paste")
			(roundrect_rratio 0.25)
			(net 1 "GND")
			(pintype "passive")
		)
		(pad "2" smd roundrect
			(at 0.48 0)
			(size 0.59 0.64)
			(layers "F.Cu" "F.Mask" "F.Paste")
			(roundrect_rratio 0.25)
			(net 727 "+1V2")
			(pintype "passive")
		)
	)
	(footprint "antmicro-footprints:C_0402_1005Metric"
		(layer "F.Cu")
		(at 228.25 151.9 180)
		(descr "Capacitor SMD 0402")
		(tags "capacitor SMD 0402")
		(property "Reference" "C258"
			(at -1.85 -1.25 0)
			(layer "F.SilkS")
			(effects
				(font
					(size 0.7 0.7)
					(thickness 0.15)
				)
				(justify right bottom)
			)
		)
		(property "Value" "C_22p_0402"
			(at 0 1.4 0)
			(layer "F.Fab")
			(effects
				(font
					(size 0.7 0.7)
					(thickness 0.15)
				)
				(justify right bottom)
			)
		)
		(property "Description" "SMD Multilayer Ceramic Capacitor, 22 pF, 50 V, 0402 [1005 Metric], ± 5%, C0G / NP0, CC Series"
			(at 0 0 180)
			(layer "F.Fab")
			(hide yes)
			(effects
				(font
					(size 1.27 1.27)
					(thickness 0.15)
				)
			)
		)
		(property "Author" "Antmicro"
			(at 456.5 303.8 0)
			(layer "F.Fab")
			(hide yes)
			(effects
				(font
					(size 1 1)
					(thickness 0.15)
				)
			)
		)
		(property "Dielectric" ""
			(at 456.5 303.8 0)
			(layer "F.Fab")
			(hide yes)
			(effects
				(font
					(size 1 1)
					(thickness 0.15)
				)
			)
		)
		(property "License" "Apache-2.0"
			(at 456.5 303.8 0)
			(layer "F.Fab")
			(hide yes)
			(effects
				(font
					(size 1 1)
					(thickness 0.15)
				)
			)
		)
		(property "MPN" "CC0402JRNPO9BN220"
			(at 456.5 303.8 0)
			(layer "F.Fab")
			(hide yes)
			(effects
				(font
					(size 1 1)
					(thickness 0.15)
				)
			)
		)
		(property "Manufacturer" "YAGEO"
			(at 456.5 303.8 0)
			(layer "F.Fab")
			(hide yes)
			(effects
				(font
					(size 1 1)
					(thickness 0.15)
				)
			)
		)
		(property "Val" "22p"
			(at 456.5 303.8 0)
			(layer "F.Fab")
			(hide yes)
			(effects
				(font
					(size 1 1)
					(thickness 0.15)
				)
			)
		)
		(property "Voltage" ""
			(at 456.5 303.8 0)
			(layer "F.Fab")
			(hide yes)
			(effects
				(font
					(size 1 1)
					(thickness 0.15)
				)
			)
		)
		(sheetname "HDMI + Ethernet")
		(sheetfile "hdmi-ethernet.kicad_sch")
		(attr smd)
		(fp_rect
			(start -0.925 -0.47)
			(end 0.925 0.47)
			(stroke
				(width 0.05)
				(type default)
			)
			(fill no)
			(layer "F.CrtYd")
		)
		(fp_line
			(start 0.504 0.248)
			(end -0.494 0.248)
			(stroke
				(width 0.15)
				(type solid)
			)
			(layer "F.Fab")
		)
		(fp_line
			(start 0.504 -0.25)
			(end 0.504 0.248)
			(stroke
				(width 0.15)
				(type solid)
			)
			(layer "F.Fab")
		)
		(fp_line
			(start -0.494 0.248)
			(end -0.494 -0.25)
			(stroke
				(width 0.15)
				(type solid)
			)
			(layer "F.Fab")
		)
		(fp_line
			(start -0.494 -0.25)
			(end 0.504 -0.25)
			(stroke
				(width 0.15)
				(type solid)
			)
			(layer "F.Fab")
		)
		(pad "1" smd roundrect
			(at -0.48 0 180)
			(size 0.59 0.64)
			(layers "F.Cu" "F.Mask" "F.Paste")
			(roundrect_rratio 0.25)
			(net 1 "GND")
			(pintype "passive")
		)
		(pad "2" smd roundrect
			(at 0.48 0 180)
			(size 0.59 0.64)
			(layers "F.Cu" "F.Mask" "F.Paste")
			(roundrect_rratio 0.25)
			(net 719 "/HDMI + Ethernet/ETH_XO")
			(pintype "passive")
		)
	)
	(footprint "antmicro-footprints:LED_0603_1608Metric_G"
		(layer "F.Cu")
		(at 207.99 74.97 90)
		(descr "LED SMD 0603 Green")
		(tags "LED SMD 0603 Green")
		(property "Reference" "D1"
			(at -2.23 0.76 0)
			(layer "F.SilkS")
			(effects
				(font
					(size 0.7 0.7)
					(thickness 0.15)
				)
				(justify right bottom)
			)
		)
		(property "Value" "LED_G_0603_KP-1608CGCK"
			(at 0 1.6 90)
			(layer "F.Fab")
			(effects
				(font
					(size 0.7 0.7)
					(thickness 0.15)
				)
				(justify left bottom)
			)
		)
		(property "Description" "LED, Green, SMD, 0603, 20 mA, 2.1 V, 570 nm"
			(at 0 0 90)
			(layer "F.Fab")
			(hide yes)
			(effects
				(font
					(size 1.27 1.27)
					(thickness 0.15)
				)
			)
		)
		(property "Author" "Antmicro"
			(at 282.96 -133.02 0)
			(layer "F.Fab")
			(hide yes)
			(effects
				(font
					(size 1 1)
					(thickness 0.15)
				)
			)
		)
		(property "Color" "Green"
			(at 282.96 -133.02 0)
			(layer "F.Fab")
			(hide yes)
			(effects
				(font
					(size 1 1)
					(thickness 0.15)
				)
			)
		)
		(property "License" "Apache-2.0"
			(at 282.96 -133.02 0)
			(layer "F.Fab")
			(hide yes)
			(effects
				(font
					(size 1 1)
					(thickness 0.15)
				)
			)
		)
		(property "MPN" "KP-1608CGCK"
			(at 282.96 -133.02 0)
			(layer "F.Fab")
			(hide yes)
			(effects
				(font
					(size 1 1)
					(thickness 0.15)
				)
			)
		)
		(property "Manufacturer" "Kingbright"
			(at 282.96 -133.02 0)
			(layer "F.Fab")
			(hide yes)
			(effects
				(font
					(size 1 1)
					(thickness 0.15)
				)
			)
		)
		(sheetname "FPGA Config")
		(sheetfile "fpga-config.kicad_sch")
		(attr smd)
		(fp_line
			(start 0.22 -0.35)
			(end -0.22 -0.35)
			(stroke
				(width 0.15)
				(type solid)
			)
			(layer "F.SilkS")
		)
		(fp_line
			(start -1.18 -0.319)
			(end -1.18 0.321)
			(stroke
				(width 0.15)
				(type solid)
			)
			(layer "F.SilkS")
		)
		(fp_line
			(start 0.105328 0.001008)
			(end 0.24 0.001)
			(stroke
				(width 0.1)
				(type solid)
			)
			(layer "F.SilkS")
		)
		(fp_line
			(start -0.094672 0.001008)
			(end 0.105328 -0.198992)
			(stroke
				(width 0.1)
				(type solid)
			)
			(layer "F.SilkS")
		)
		(fp_line
			(start -0.094672 0.001008)
			(end -0.24 0.001008)
			(stroke
				(width 0.1)
				(type solid)
			)
			(layer "F.SilkS")
		)
		(fp_line
			(start 0.105328 0.201008)
			(end 0.105328 -0.198992)
			(stroke
				(width 0.1)
				(type solid)
			)
			(layer "F.SilkS")
		)
		(fp_line
			(start 0.105328 0.201008)
			(end -0.094672 0.001008)
			(stroke
				(width 0.1)
				(type solid)
			)
			(layer "F.SilkS")
		)
		(fp_line
			(start -0.094672 0.201008)
			(end -0.094672 -0.198992)
			(stroke
				(width 0.1)
				(type solid)
			)
			(layer "F.SilkS")
		)
		(fp_line
			(start 0.22 0.35)
			(end -0.22 0.35)
			(stroke
				(width 0.15)
				(type solid)
			)
			(layer "F.SilkS")
		)
		(fp_rect
			(start 1.25 0.65)
			(end -1.25 -0.65)
			(stroke
				(width 0.05)
				(type solid)
			)
			(fill no)
			(layer "F.CrtYd")
		)
		(fp_line
			(start 0.201 -0.202)
			(end -0.101 0)
			(stroke
				(width 0.15)
				(type solid)
			)
			(layer "F.Fab")
		)
		(fp_line
			(start -0.199 -0.202)
			(end -0.199 0.1)
			(stroke
				(width 0.15)
				(type solid)
			)
			(layer "F.Fab")
		)
		(fp_line
			(start 0.599 0)
			(end 0.201 0)
			(stroke
				(width 0.15)
				(type solid)
			)
			(layer "F.Fab")
		)
		(fp_line
			(start 0.201 0)
			(end 0.201 -0.202)
			(stroke
				(width 0.15)
				(type solid)
			)
			(layer "F.Fab")
		)
		(fp_line
			(start -0.101 0)
			(end 0.201 0.2)
			(stroke
				(width 0.15)
				(type solid)
			)
			(layer "F.Fab")
		)
		(fp_line
			(start -0.199 0)
			(end -0.597 0)
			(stroke
				(width 0.15)
				(type solid)
			)
			(layer "F.Fab")
		)
		(fp_line
			(start 0.201 0.2)
			(end 0.201 0)
			(stroke
				(width 0.15)
				(type solid)
			)
			(layer "F.Fab")
		)
		(fp_line
			(start -0.199 0.2)
			(end -0.199 0.1)
			(stroke
				(width 0.15)
				(type solid)
			)
			(layer "F.Fab")
		)
		(fp_rect
			(start 0.848 0.4)
			(end -0.85 -0.402)
			(stroke
				(width 0.15)
				(type solid)
			)
			(fill no)
			(layer "F.Fab")
		)
		(pad "1" smd roundrect
			(at -0.7 0 270)
			(size 0.8 1)
			(layers "F.Cu" "F.Mask" "F.Paste")
			(roundrect_rratio 0.2)
			(net 17 "Net-(D1-C)")
			(pinfunction "C")
			(pintype "passive")
		)
		(pad "2" smd roundrect
			(at 0.7 0 270)
			(size 0.8 1)
			(layers "F.Cu" "F.Mask" "F.Paste")
			(roundrect_rratio 0.2)
			(net 24 "+3V3")
			(pinfunction "A")
			(pintype "passive")
		)
	)
	(footprint "antmicro-footprints:R_0402_1005Metric"
		(layer "F.Cu")
		(at 224.4 154 90)
		(descr "Resistor SMD 0402")
		(tags "resistor SMD 0402")
		(property "Reference" "R244"
			(at -1.6 1.2 90)
			(layer "F.SilkS")
			(effects
				(font
					(size 0.7 0.7)
					(thickness 0.15)
				)
				(justify left bottom)
			)
		)
		(property "Value" "R_12k_0402"
			(at 0 1.4 90)
			(layer "F.Fab")
			(effects
				(font
					(size 0.7 0.7)
					(thickness 0.15)
				)
				(justify left bottom)
			)
		)
		(property "Description" "SMD Chip Resistor, 12 kohm, ± 1%, 62.5 mW, 0402 [1005 Metric], Thick Film, General Purpose"
			(at 0 0 90)
			(layer "F.Fab")
			(hide yes)
			(effects
				(font
					(size 1.27 1.27)
					(thickness 0.15)
				)
			)
		)
		(property "Author" "Antmicro"
			(at 378.4 -70.4 0)
			(layer "F.Fab")
			(hide yes)
			(effects
				(font
					(size 1 1)
					(thickness 0.15)
				)
			)
		)
		(property "License" "Apache-2.0"
			(at 378.4 -70.4 0)
			(layer "F.Fab")
			(hide yes)
			(effects
				(font
					(size 1 1)
					(thickness 0.15)
				)
			)
		)
		(property "MPN" "CR0402-FX-1202GLF"
			(at 378.4 -70.4 0)
			(layer "F.Fab")
			(hide yes)
			(effects
				(font
					(size 1 1)
					(thickness 0.15)
				)
			)
		)
		(property "Manufacturer" "Bourns"
			(at 378.4 -70.4 0)
			(layer "F.Fab")
			(hide yes)
			(effects
				(font
					(size 1 1)
					(thickness 0.15)
				)
			)
		)
		(property "Tolerance" "1%"
			(at 378.4 -70.4 0)
			(layer "F.Fab")
			(hide yes)
			(effects
				(font
					(size 1 1)
					(thickness 0.15)
				)
			)
		)
		(property "Val" "12k"
			(at 378.4 -70.4 0)
			(layer "F.Fab")
			(hide yes)
			(effects
				(font
					(size 1 1)
					(thickness 0.15)
				)
			)
		)
		(sheetname "HDMI + Ethernet")
		(sheetfile "hdmi-ethernet.kicad_sch")
		(attr smd)
		(fp_rect
			(start -0.925 -0.47)
			(end 0.925 0.47)
			(stroke
				(width 0.05)
				(type default)
			)
			(fill no)
			(layer "F.CrtYd")
		)
		(fp_rect
			(start -0.5 -0.25)
			(end 0.5 0.25)
			(stroke
				(width 0.15)
				(type solid)
			)
			(fill no)
			(layer "F.Fab")
		)
		(pad "1" smd roundrect
			(at -0.48 0 90)
			(size 0.59 0.64)
			(layers "F.Cu" "F.Mask" "F.Paste")
			(roundrect_rratio 0.25)
			(net 1 "GND")
			(pintype "passive")
		)
		(pad "2" smd roundrect
			(at 0.48 0 90)
			(size 0.59 0.64)
			(layers "F.Cu" "F.Mask" "F.Paste")
			(roundrect_rratio 0.25)
			(net 952 "/HDMI + Ethernet/ETH_ISET")
			(pintype "passive")
		)
	)
	(footprint "antmicro-footprints:R_0402_1005Metric"
		(layer "F.Cu")
		(at 228.517121 158 90)
		(descr "Resistor SMD 0402")
		(tags "resistor SMD 0402")
		(property "Reference" "R50"
			(at 2.175 0.382879 90)
			(layer "F.SilkS")
			(effects
				(font
					(size 0.7 0.7)
					(thickness 0.15)
				)
				(justify left bottom)
			)
		)
		(property "Value" "R_100k_0402"
			(at 0 1.4 90)
			(layer "F.Fab")
			(effects
				(font
					(size 0.7 0.7)
					(thickness 0.15)
				)
				(justify left bottom)
			)
		)
		(property "Description" "SMD Chip Resistor, 100 kohm, ± 1%, 62.5 mW, 0402 [1005 Metric], Thick Film, General Purpose"
			(at 0 0 90)
			(layer "F.Fab")
			(hide yes)
			(effects
				(font
					(size 1.27 1.27)
					(thickness 0.15)
				)
			)
		)
		(property "Author" "Antmicro"
			(at 386.517121 -70.517121 0)
			(layer "F.Fab")
			(hide yes)
			(effects
				(font
					(size 1 1)
					(thickness 0.15)
				)
			)
		)
		(property "License" "Apache-2.0"
			(at 386.517121 -70.517121 0)
			(layer "F.Fab")
			(hide yes)
			(effects
				(font
					(size 1 1)
					(thickness 0.15)
				)
			)
		)
		(property "MPN" "CR0402-FX-1003GLF"
			(at 386.517121 -70.517121 0)
			(layer "F.Fab")
			(hide yes)
			(effects
				(font
					(size 1 1)
					(thickness 0.15)
				)
			)
		)
		(property "Manufacturer" "Bourns"
			(at 386.517121 -70.517121 0)
			(layer "F.Fab")
			(hide yes)
			(effects
				(font
					(size 1 1)
					(thickness 0.15)
				)
			)
		)
		(property "Tolerance" "1%"
			(at 386.517121 -70.517121 0)
			(layer "F.Fab")
			(hide yes)
			(effects
				(font
					(size 1 1)
					(thickness 0.15)
				)
			)
		)
		(property "Val" "100k"
			(at 386.517121 -70.517121 0)
			(layer "F.Fab")
			(hide yes)
			(effects
				(font
					(size 1 1)
					(thickness 0.15)
				)
			)
		)
		(sheetname "Power supply")
		(sheetfile "power-supply.kicad_sch")
		(attr smd)
		(fp_rect
			(start -0.925 -0.47)
			(end 0.925 0.47)
			(stroke
				(width 0.05)
				(type default)
			)
			(fill no)
			(layer "F.CrtYd")
		)
		(fp_rect
			(start -0.5 -0.25)
			(end 0.5 0.25)
			(stroke
				(width 0.15)
				(type solid)
			)
			(fill no)
			(layer "F.Fab")
		)
		(pad "1" smd roundrect
			(at -0.48 0 90)
			(size 0.59 0.64)
			(layers "F.Cu" "F.Mask" "F.Paste")
			(roundrect_rratio 0.25)
			(net 872 "/Power supply/SINK_EN")
			(pintype "passive")
		)
		(pad "2" smd roundrect
			(at 0.48 0 90)
			(size 0.59 0.64)
			(layers "F.Cu" "F.Mask" "F.Paste")
			(roundrect_rratio 0.25)
			(net 5 "/Power supply/PD_VBUS")
			(pintype "passive")
		)
	)
)
